5
5
4
4
3
3
2
2
1
1
D D
C C
B B
A A
FAN Control Board 
LED DRIVER 
PCA9551 
EEPROM 
24LC64T 
I2C_C 
4P20S CONN 
NCT7904D TACH X12 
PWM_EXP_1A 
PWM_EXP_1B 
PWM_EXP_2A 
PWM_EXP_2B 
PWM_OUT 
FAN 
X 6 
NCT7368S 
THERMHOT# 
FAN MONITOR 
CURRENT SHUNT 
HOT-SWAP 
ADM1276 
PAGE02:Power Map 
PAGE06:I2C_Devices 
PAGE01:Block diagram 
PAGE03:FAN MONITOR NCT7904D 
PAGE04:PWM Compare NCT7368S 
PAGE05:P3V3&LEDs 
PAGE07:PWR&SIGNAL CONN 
PAGE08:HOT_SWAP  ADM1276 
PAGE09:FAN_CONN 
PAGE10:12V_HOT_SWAP 
PAGE11:Screws 
PAGE12:BLANK 
Buffer 
TSLV07 
PAGE13:BLANK 
GATE 
OR 
PWM SIGNAL SOURCE 
DEFAULT: PATH#1 
RESERVE: PATH#2 
1 2
GATE 
GATE 
OR 
OR 
SELF_1A_HB 
SELF_1B_HB 
SELF_2A_HB 
SELF_2B_HB 
PAGE14:BLANK 
Title 
Size 
Document Number R ev 
Date: Sheet o f 
Honey_Badger_FCB 1
BLOCK_DIAGRAM
C
1 13Friday, January 30, 2015
Wiwynn
H/W R&D Dept. II
8F,90,Sec. 1,Hsin Tai Wu Rd,
Hsichih, Taipei Hsien 221, Taiwan, R.O.C
Title 
Size 
Document Number R ev 
Date: Sheet o f 
Honey_Badger_FCB 1
BLOCK_DIAGRAM
C
1 13Friday, January 30, 2015
Wiwynn
H/W R&D Dept. II
8F,90,Sec. 1,Hsin Tai Wu Rd,
Hsichih, Taipei Hsien 221, Taiwan, R.O.C
Title 
Size 
Document Number R ev 
Date: Sheet o f 
Honey_Badger_FCB 1
BLOCK_DIAGRAM
C
1 13Friday, January 30, 2015
Wiwynn
H/W R&D Dept. II
8F,90,Sec. 1,Hsin Tai Wu Rd,
Hsichih, Taipei Hsien 221, Taiwan, R.O.C



5
5
4
4
3
3
2
2
1
1
D D
C C
B B
A A
POWER MAP 
P12V_AUX 
BUS BAR 
    PU1 
ADM1276-3ACPZ 
    PU6 
TPS2490DGSR 
     PU7 
TPS2490DGSR 
DY=Dummy parts 
  =not populated 
562R2F- GP 
562 = 562 ohm, (2K2R means 2.2K ohm) 
2 = size 0402 
F = 1% tolerance 
GP= Green Part (RoHS) 
RC size code as below: 
1 = 0201 
2= 0402 
3= 0603 
5= 0805 
6= 1206 
R tolerance code as below: 
D=0.5% 
F= 1% 
J= 5% 
SCD1U10V2KX-5GP 
D1U = 0.1uF (2D2U means 2.2uF) 
10Voltage (6D3V means 6.3V) 
2 = size 0402, K tolerance 
K=tolerance 
[ C code as below:] 
G=2% 
J=5% 
K=10% 
M=20% 
X=temp characteristics 
[ C Series/Temp] 
N=NPO 
X=X7R/X5R 
Y=Y5V 
-5=different symbol/customer 
GP= Green Part (RoHS) 
  U4 
SY8021 
EEPROM 
P12V 
 POWER CONN 
 51952-220LF 
 POWER CONN 
 51952-220LF 
FAN CONN 
12V 
LED 
LED DRIVER 
FAN MONITOR 
PWM COMPARER 
P12VU P12VL 
Title 
Size Document Number R e v 
Date: Sheet 
o f 
Honey_Badger_FCB 1
Power Map
A3
2 13Friday, January 30, 2015
Wiwynn
H/W R&D Dept. II
8F,90,Sec. 1,Hsin Tai Wu Rd,
Hsichih, Taipei Hsien 221, Taiwan, R.O.C
Title 
Size Document Number R e v 
Date: Sheet 
o f 
Honey_Badger_FCB 1
Power Map
A3
2 13Friday, January 30, 2015
Wiwynn
H/W R&D Dept. II
8F,90,Sec. 1,Hsin Tai Wu Rd,
Hsichih, Taipei Hsien 221, Taiwan, R.O.C
Title 
Size Document Number R e v 
Date: Sheet 
o f 
Honey_Badger_FCB 1
Power Map
A3
2 13Friday, January 30, 2015
Wiwynn
H/W R&D Dept. II
8F,90,Sec. 1,Hsin Tai Wu Rd,
Hsichih, Taipei Hsien 221, Taiwan, R.O.C



5
5
4
4
3
3
2
2
1
1
D D
C C
B B
A A
Operating current: 10mA 
FAN CONTROLLER 
NCT7904_3VDD
NCT7904_TMPALM
NCT7904_CLKIN
NCT7904_D1+
NCT7904_D1-
NCT7904_D1+
NCT7904_D1-
NCT7904_ADR
I2C_C_SCL_NCT7904
I2C_C_SDA_NCT7904
NCT7904_CASEOPEN 
NCT7904_RESET
OSC_TRI_S
NCT7904_D2-
NCT7904D_PWM1
NCT7904D_PWM2
NCT7904D_PWM3
NCT7904D_PWM4
NCT7904_PECI
NCT7904_LED
NCT7904_D2+
NCT7904_VSEN8
NCT7904_VSEN7
NCT7904_VSEN9
NCT7904_VSEN10
NCT7904_VSEN11
NCT7904_VSEN12
NCT7904_VSEN13
NCT7904_VSEN14
NCT7904_THERMTRIP
NCT7904_PROCHOT
NCT7904_3VSB
NCT7904_GND
NCT7904_D2+
NCT7904_D2-
NCT7904_3VSB
NCT7904_SMI
NCT7904_CLK
NCT7904_RSTOUT
NCT7904_VSEN6
NCT7904_VSEN1
NCT7904_VREF
NCT7904_VSEN7
NCT7904_VSEN9NCT7904_VSEN_P12V_AUX
P3V3
P3V3
P3V3
P3V3
P3V3
P12VL
P12VU
P12V_AUX
FANIN_11 9
FANIN_12 9
FANIN_9 9
FANIN_10 9
FANIN_7 9
FANIN_6 9
FANIN_8 9
FANIN_5 9
FANIN_3 9
FANIN_4 9
I2C_C_SCL 6,7,8
I2C_C_SDA 6,7,8
FANIN_19
FANIN_29
TEMP_ALM# 8,10
NCT7904D_PWM1 4
NCT7904D_PWM2 4
NCT7904D_PWM3 4
Title 
Size 
Document Number R ev 
Date: Sheet o f 
Honey_Badger_FCB 1
FAN MONITOR NCT7904D
C
3 13Friday, January 30, 2015
Wiwynn
H/W R&D Dept. II
8F,90,Sec. 1,Hsin Tai Wu Rd,
Hsichih, Taipei Hsien 221, Taiwan, R.O.C
Title 
Size 
Document Number R ev 
Date: Sheet o f 
Honey_Badger_FCB 1
FAN MONITOR NCT7904D
C
3 13Friday, January 30, 2015
Wiwynn
H/W R&D Dept. II
8F,90,Sec. 1,Hsin Tai Wu Rd,
Hsichih, Taipei Hsien 221, Taiwan, R.O.C
Title 
Size 
Document Number R ev 
Date: Sheet o f 
Honey_Badger_FCB 1
FAN MONITOR NCT7904D
C
3 13Friday, January 30, 2015
Wiwynn
H/W R&D Dept. II
8F,90,Sec. 1,Hsin Tai Wu Rd,
Hsichih, Taipei Hsien 221, Taiwan, R.O.C
R5
0R2J-2-GP
12
R15
10KR2F-2-GP
1 2
TP12
TPAD32-GP1
TP14TPAD32-GP 1
C3 
SC10U25V5KX-GP 
1 2
R9
100KR2J-1-GP
DY
1 2
TP13TPAD32-GP 1
C4
SCD1U16V2KX-3GP 
1 2
TP11TPAD32-GP 1
R10
1MR2J-1-GP
1 2
R7 0R2J-2-GP DY1 2
TP10TPAD32-GP 1
TP17TPAD32-GP 1 R6 0R2J-2-GP DY1 2
Q1 PMBS3904-1-GP 
3
1
2
R35
10KR2F-2-GP
1 2
C7 
SC2200P50V2KX-2GP 
1 2
1
R2
0R2J-2-GP
1 2
R14
110KR2F-L-GP
1 2
TP5TPAD32-GP
1
L1
FCM1608CF-121T03-GP
1 2
TP6
TPAD32-GP
1
C1 
SC10U25V5KX-GP 
1 2
C6
SC4D7U6D3V2MX-GP-U
1 2
TP15TPAD32-GP 1
U1
NCT7904D-GP
VREF1
TR1/D1+/VSEN22
D1-/VSEN33
TR2/D2+/VSEN44
D2-/VSEN55
TR3/VSEN66
VSEN77
TR4/VSEN88
VSEN99
VSEN1010
VSEN1111
VSEN1212
VSEN1313
VSEN1414
3VDD 15 
3VSB 16 
GPIOF/SMI# 17P1_PROCHOT#18
VTT/VSEN1 19 
PECI/GPIO16/SCL_TSI 20
P1_THERMTRIP#/SDA_TSI21
CLKIN/14_318M_33M_48M 22
S_SMB_CLK 23 S_SMB_DAT 24 
M_SMB_CLK/FANIN_11/LED_EVNT_IN25
M_SMB_DATA/FANIN_12/LED_OUT26
ADD0 27 
WDT_RSTOUT#/GPIOG/VSEN17 28
FANIN_1 29
PWM1 30
FANIN_2 31
PWM2 32
FANIN_3 33
PWM3/VSEN18 34
FANIN_4 35
PWM4/DCOUT/VSEN19 36
FANIN_5/GPIO13 37
GPIO14/FANIN_6 38
GPIO15/FANIN_7 39
FANIN_8/GPIOA 40
VOLT_ALM#/FANIN_9/GPIOB 41
FAN_ALM#/FANIN_10/GPIOC 42
GND 43 
TEMP_ALM#/GPIOD 44
BEEP/GPIOE/LED 45
RESTIN# 46 
CASEOPEN# 47 
VBAT 48 
L2
FCM1608CF-121T03-GP
1 2 R50
0R2J-2-GP
DY
1 2
R11
100KR2J-1-GP
1 2
TP1
TPAD32-GP
1
Q2 PMBS3904-1-GP 
3
1
2
C2
SCD1U16V2KX-3GP
1 2
R128
10KR2F-2-GP
1 2
C5
SCD1U16V2KX-3GP 
1 2
R36
110KR2F-L-GP
1 2
R16
110KR2F-L-GP
1 2
R12
4K7R2F-GP
1 2
R4 0R2J-2-GP1 2
OSC1
OSC-33MHZ-7-GP
TRI-S1 VDD 4
GND2 OUT 3
TP16
TPAD32-GP
1
R8
0R5J-5-GP
1 2
C8 
SC2200P50V2KX-2GP 
1 2
R51
0R2J-2-GP
1 2
R1
0R2J-2-GP
1 2
R3
4K7R2F-GP
1 2



5
5
4
4
3
3
2
2
1
1
D D
C C
B B
A A
PWM_EXP_1A
PWM_EXP_1B
PWM_EXP_2A
NCT7368S_SEL
PWM_OUT
PWM_BUFFER_IN_FAN5_FAN6
PWM_BUFFER_IN_FAN1_FAN2
PWM_OUT
PWM_BUFFER_IN_FAN3_FAN4
THERMHOT#
SEB_PEER_1A_1B_HB_OUT
SEB_PEER_2A_2B_HB_OUT
THERMHOT#_R
P3V3
P3V3
P3V3P3V3
P3V3
P3V3
P3V3
P3V3
P3V3
P3V3
PWM_EXP_1A7
PWM_EXP_1B7
PWM_EXP_2A7
PWM_EXP_2B 7
NCT7904D_PWM13
NCT7904D_PWM23
NCT7904D_PWM33
PWM_OUT_FAN6 9
PWM_OUT_FAN5 9
PWM_OUT_FAN4 9
PWM_OUT_FAN3 9
PWM_OUT_FAN2 9
PWM_OUT_FAN1 9
SEB_PEER_1A_HB7
SEB_PEER_1B_HB7
SEB_PEER_2B_HB7
SEB_PEER_2A_HB7
Title 
Size 
Document Number Rev 
Date: Sheet o f 
Honey_Badger_FCB 1
PWM Compare NCT7368S
C
4 13Friday, January 30, 2015
Wiwynn
H/W R&D Dept. II
8F,90,Sec. 1,Hsin Tai Wu Rd,
Hsichih, Taipei Hsien 221, Taiwan, R.O.C
Title 
Size 
Document Number Rev 
Date: Sheet o f 
Honey_Badger_FCB 1
PWM Compare NCT7368S
C
4 13Friday, January 30, 2015
Wiwynn
H/W R&D Dept. II
8F,90,Sec. 1,Hsin Tai Wu Rd,
Hsichih, Taipei Hsien 221, Taiwan, R.O.C
Title 
Size 
Document Number Rev 
Date: Sheet o f 
Honey_Badger_FCB 1
PWM Compare NCT7368S
C
4 13Friday, January 30, 2015
Wiwynn
H/W R&D Dept. II
8F,90,Sec. 1,Hsin Tai Wu Rd,
Hsichih, Taipei Hsien 221, Taiwan, R.O.C
R130 
4K7R2F-GP 
1 2
C16
SCD1U50V3KX-GP
1 2
C9
SC1U16V3KX-5GP 
1 2
R1610R2J-2-GP DY1 2
R176
0R2J-2-GP
12
C11
SCD1U50V3KX-GP
1 2
C10
SCD1U50V3KX-GP 
1 2
R21
100KR2F-L1-GP
1 2
R114 
470R2F-GP 
1 2
R167
4K7R2F-GP 
DY
1 2
R1620R2J-2-GP DY1 2
C53 
SC1U16V3KX-5GP 
1 2
C15
SC1U16V3KX-5GP
1 2
R17
100KR2F-L1-GP
1 2
U11
74LVC1G32GW-1GP
A2
B1
GND3 Y 4
VCC 5
C55 
SC1U16V3KX-5GP 
1 2
U7
TSLV07APWR-GP
1A1 1Y 2
2A3 2Y 4
3A5 3Y 6
GND 7
4Y 84A9
5Y 105A11
6Y 126A13
VCC14
R120 
470R2F-GP 
1 2
R134 
4K7R2F-GP 
1 2
R24
4K7R2F-GP
DY
1 2
R118 
470R2F-GP 
1 2
U2
NCT7368S-GP
VCC1
PWMIN12
PWMIN23
PWMIN34 SEL 5THERMHOT# 6PWMOUT 7PWMIN4 8GND 9
R132 
4K7R2F-GP 
1 2
C12
SC1U16V3KX-5GP
1 2
R116 
470R2F-GP 
1 2
R18
100KR2F-L1-GP
1 2
R183
0R2J-2-GP
12
R166
4K7R2F-GP 
DY
1 2
R22
4K7R2F-GP
DY
1 2
R164
0R2J-2-GP
12
C52 
SCD1U50V3KX-GP 
1 2
R49
4K7R2F-GP
DY
1 2
R1630R2J-2-GP DY1 2
R52
4K7R2F-GP
DY
1 2
C54 
SCD1U50V3KX-GP 
1 2
U3
74LVC1G32GW-1GP
A2
B1
GND3 Y 4
VCC 5
R20
4K7R2F-GP 
1 2
R135 
4K7R2F-GP 
1 2
R19
100KR2F-L1-GP
1 2
R165
0R2J-2-GP
12
R133 
4K7R2F-GP 
1 2
U10
74LVC1G32GW-1GP
A2
B1
GND3 Y 4
VCC 5
R131 
4K7R2F-GP 
1 2
R23
4K7R2F-GP
DY
1 2



5
5
4
4
3
3
2
2
1
1
D D
C C
B B
A A
LED_DR_LED5_K
LED_DR_LED4_K
LED_DR_LED0_K
P3V3_FB
P3V3_IN
P3V3_BS_NET
P3V3_LX_REV 
P3V3_LX_COPPERP3V3_LX
P3V3_EN
LED_DR_LED3_K
LED_DR_LED1_K
LED_DR_LED4_BLUE
LED_DR_LED2_BLUE
LED_DR_LED1_BLUE
LED_DR_LED2_K
LED_DR_LED3_BLUE
LED_DR_LED5_BLUE
LED_DR_LED0_BLUE
LED_DR_LED0_B
LED_DR_LED1_B
LED_DR_LED2_B
LED_DR_LED3_B
LED_DR_LED4_B
LED_DR_LED5_B
P3V3
P3V3
P12V
P3V3
P3V3
P3V3
P3V3P3V3
P12V
P12V
P12V
P12V
P12V
P12V
LED_DR_LED56
LED_DR_LED46
LED_DR_LED36
LED_DR_LED26
LED_DR_LED16
LED_DR_LED06
Title 
Size 
Document Number Rev 
Date: Sheet o f 
Honey_Badger_FCB 1
P3V3&LEDs
C
5 13Friday, January 30, 2015
Wiwynn
H/W R&D Dept. II
8F,90,Sec. 1,Hsin Tai Wu Rd,
Hsichih, Taipei Hsien 221, Taiwan, R.O.C
Title 
Size 
Document Number Rev 
Date: Sheet o f 
Honey_Badger_FCB 1
P3V3&LEDs
C
5 13Friday, January 30, 2015
Wiwynn
H/W R&D Dept. II
8F,90,Sec. 1,Hsin Tai Wu Rd,
Hsichih, Taipei Hsien 221, Taiwan, R.O.C
Title 
Size 
Document Number Rev 
Date: Sheet o f 
Honey_Badger_FCB 1
P3V3&LEDs
C
5 13Friday, January 30, 2015
Wiwynn
H/W R&D Dept. II
8F,90,Sec. 1,Hsin Tai Wu Rd,
Hsichih, Taipei Hsien 221, Taiwan, R.O.C
RED 
ANODE 
COMMON CATHODE 
BLUE 
ANODE 
LED2
LED-RB-6-GP1
2
3
R119
2KR2F-3-GP
1 2
R30
0R2J-2-GP
1 2
R32
0R2J-2-GP
1 2
RED 
ANODE 
COMMON CATHODE 
BLUE 
ANODE 
LED5
LED-RB-6-GP1
2
3
R117
2KR2F-3-GP
1 2
R38
0R2J-2-GP
1 2
R111
2KR2F-3-GP
1 2
R122
1K8R6J-GP
1 2
PC43
SC22U16V6MX-GP
1 2
R33
33R2F-3-GPDY
1 2
R113
2KR2F-3-GP
1 2
RED 
ANODE 
COMMON CATHODE 
BLUE 
ANODE 
LED3
LED-RB-6-GP1
2
3
Q5
PMBS3904-1-GP
3
1
2
RED 
ANODE 
COMMON CATHODE 
BLUE 
ANODE 
LED1
LED-RB-6-GP1
2
3
R115
2KR2F-3-GP
1 2
R123
1K8R6J-GP
1 2
PC40 
SC4D7U50V6KX-L2-GP 
1 2
R28
0R2J-2-GP
1 2
PR53
10KR3J-L1-GP
1 2
R27
33R2F-3-GPDY
1 2
R29
33R2F-3-GPDY
1 2
R125
1K8R6J-GP
1 2
R127
1K8R6J-GP
1 2
R126
1K8R6J-GP
1 2
R37
33R2F-3-GPDY
1 2
Q4
PMBS3904-1-GP
3
1
2
R154
0R0805-PAD-2-GP
1 2
Q6
PMBS3904-1-GP 
3
1
2
R121
2KR2F-3-GP
1 2
R34
0R2J-2-GP
1 2
PR57
0R0603-PAD-2-GP
1 2
PC41
SCD1U16V2KX-3GP 
1 2
PR55
100KR2F-L1-GP
1 2
PR56
22K1R3F-GP
1 2
U4
SY8201ABC-GP
BS 1 GND 2
FB 3EN4
IN5 LX 6
PC42
SC22P50V3JN-DLGP
1 2
RED 
ANODE 
COMMON CATHODE 
BLUE 
ANODE 
LED6
LED-RB-6-GP1
2
3
PL7
IND-22UH-169-GP
1 2
PR54
0R3J-0-U-GP
1 2
R124
1K8R6J-GP
1 2
PR52
47KR3F-GP
1 2
R31
33R2F-3-GPDY
1 2
RED 
ANODE 
COMMON CATHODE 
BLUE 
ANODE 
LED4
LED-RB-6-GP1
2
3
Q8
PMBS3904-1-GP
3
1
2
R25
33R2F-3-GPDY
1 2
Q3
PMBS3904-1-GP
3
1
2
Q7
PMBS3904-1-GP 
3
1
2
R26
0R2J-2-GP
1 2



5
5
4
4
3
3
2
2
1
1
D D
C C
B B
A A
FCB_EEPROM_A0
FCB_EEPROM_A1
FCB_EEPROM_A2
I2C_C_SCL_EEPROM
EEPROM_WP
I2C_C_SDA_EEPROM
I2C_C_SDA_LEDDRV
I2C_C_SCL_LEDDRV
LED_DRV_A0
LED_DRV_A1
LED_DRV_A2
LED_DRV_RST
LED_DR_LED6_RESERVE
LED_DR_LED7_RESERVE
P3V3 P3V3
P3V3
P3V3
P3V3
I2C_C_SCL 3,7,8
I2C_C_SDA 3,7,8
I2C_C_SDA3,7,8
I2C_C_SCL3,7,8
LED_DR_LED1 5
LED_DR_LED3 5
LED_DR_LED2 5
LED_DR_LED5 5
LED_DR_LED4 5
LED_DR_LED0 5
Title 
Size 
Document Number Rev 
Date: Sheet o f 
Honey_Badger_FCB 1
I2C_Devices
C
6 13Friday, January 30, 2015
Wiwynn
H/W R&D Dept. II
8F,90,Sec. 1,Hsin Tai Wu Rd,
Hsichih, Taipei Hsien 221, Taiwan, R.O.C
Title 
Size 
Document Number Rev 
Date: Sheet o f 
Honey_Badger_FCB 1
I2C_Devices
C
6 13Friday, January 30, 2015
Wiwynn
H/W R&D Dept. II
8F,90,Sec. 1,Hsin Tai Wu Rd,
Hsichih, Taipei Hsien 221, Taiwan, R.O.C
Title 
Size 
Document Number Rev 
Date: Sheet o f 
Honey_Badger_FCB 1
I2C_Devices
C
6 13Friday, January 30, 2015
Wiwynn
H/W R&D Dept. II
8F,90,Sec. 1,Hsin Tai Wu Rd,
Hsichih, Taipei Hsien 221, Taiwan, R.O.C
R129 
330R2J-3-GP 
1 2
R45
0R2J-2-GP
1 2
C14 
SCD1U50V3KX-GP 
1 2
TP19 TPAD32-GP1
R554K7R2J-2-GP 1 2
R43 
4K7R2J-2-GP 
1 2
R59 
330R2J-3-GP 
DY1 2
R156 
330R2J-3-GP 
1 2
R41 
4K7R2J-2-GP 
DY 
1 2
U5
24LC64T-I-GP
A12
A23
A01
SDA 5VSS4 SCL 6WP 7VCC 8
U6
PCA9551PW-T-2GP-U
A01
A12
A23
VSS 8
RESET#13
SCL14
SDA15
VDD16 LED0 4
LED1 5
LED2 6
LED3 7
LED4 9
LED5 10
LED6 11
LED7 12
R106
0R2J-2-GP
12
R58 
330R2J-3-GP 
DY1 2
R46
0R2J-2-GP
1 2
R44 
4K7R2J-2-GP 
1 2
TP18
TPAD32-GP
1
R39 
4K7R2J-2-GP 
1 2
R148 
330R2J-3-GP 
1 2
R155 
330R2J-3-GP 
1 2
R544K7R2J-2-GP 1 2
C20 
SCD1U50V3KX-GP 
1 2
R47
0R2J-2-GP
1 2
R42 
4K7R2J-2-GP 
DY 
1 2
C19 
SC1U16V3KX-5GP 
1 2
R48
4K7R2J-2-GP
1 2
TP26 TPAD32-GP1
C13 
SC1U16V3KX-5GP 
1 2
R149 
330R2J-3-GP 
1 2
R107
0R2J-2-GP
12
R564K7R2J-2-GP 1 2
R157 
330R2J-3-GP 
1 2
R40 
4K7R2J-2-GP 
DY 
1 2



5
5
4
4
3
3
2
2
1
1
D D
C C
B B
A A
HARDWARE REVISION 
0 For normal storage 
1 For cold storage 
TRAY ID 
0 for Lower Tray 
1 for Upper Tray 
Lower Tray ID detection Upper Tray ID detection 
SEB_PEER_1B_HB
FCB_HW_REVISION
SELF_1B_HB
UPPER_TRAY_ID
PEER_TRAY PRESENT_UPPER
SELF_TRAY_PRESENT_UPPER
SELF_TRAY_PRESENT_LOWER
P12VU_2490_EN_1
FCB_HW_REVISION
LOWER_TRAY_IDUPPER_TRAY_ID
I2C_C_SDA_CONN_R
I2C_C_SCL_CONN_R
PWM_EXP_1B
P12VU_2490_EN_2
PWM_EXP_2B
P12VL_2490_EN_1
P12VL_2490_EN_2
I2C_C_SDA_CONN_R
SEB_PEER_2B_HB
SELF_2B_HB
FCB_HW_REVISION
LOWER_TRAY_ID
PEER_TRAY PRESENT_LOWER SELF_TRAY_PRESENT_UPPER
SELF_TRAY_PRESENT_LOWER
SEB_PEER_2A_HB
I2C_C_SCL_CONN_R
PWM_EXP_1A
SEB_PEER_1A_HB
SELF_1A_HB
PWM_EXP_2A
SELF_2A_HB
SD_LATCH_RELEASE_L
SD_LATCH_RELEASE_U
I2C_C_SDA_CONN_R
I2C_C_SCL_CONN_R
P12VU
P12V_AUX
P3V3
P3V3P3V3
P12VL
P3V3
TEMP_ALM#_REVERSE_R 8
SEB_PEER_2B_HB4
PWM_EXP_1B4
PWM_EXP_2B4
SEB_PEER_1B_HB4
P12VU_2490_EN_1 10
P12VU_2490_EN_2 10
P12VL_2490_EN_1 10
P12VL_2490_EN_2 10
PWM_EXP_1A4
SEB_PEER_2A_HB 4
PWM_EXP_2A4
SEB_PEER_1A_HB 4
TEMP_ALM#_REVERSE_R 8
D_LATCH_PRE# 10
D_LATCH_PRE# 10
I2C_C_SDA 3,6,8
I2C_C_SCL 3,6,8
Title 
Size 
Document Number Rev 
Date: Sheet o f 
Honey_Badger_FCB 1
CONN
C
7 13Friday, January 30, 2015
Wiwynn
H/W R&D Dept. II
8F,90,Sec. 1,Hsin Tai Wu Rd,
Hsichih, Taipei Hsien 221, Taiwan, R.O.C
Title 
Size 
Document Number Rev 
Date: Sheet o f 
Honey_Badger_FCB 1
CONN
C
7 13Friday, January 30, 2015
Wiwynn
H/W R&D Dept. II
8F,90,Sec. 1,Hsin Tai Wu Rd,
Hsichih, Taipei Hsien 221, Taiwan, R.O.C
Title 
Size 
Document Number Rev 
Date: Sheet o f 
Honey_Badger_FCB 1
CONN
C
7 13Friday, January 30, 2015
Wiwynn
H/W R&D Dept. II
8F,90,Sec. 1,Hsin Tai Wu Rd,
Hsichih, Taipei Hsien 221, Taiwan, R.O.C
H10
HOLE
1
R63
0R2J-2-GP
12
R185 0R2J-2-GP
DY
1 2
R357
10KR2F-2-GP
DY
1 2
CN9
FCI-CONN52-4R-1-GP
P1_1
P1_2 P1_3
P1_4
P1_5
P1_6 P1_7
P1_8
P2_1
P2_2 P2_3
P2_4
P2_5
P2_6 P2_7
P2_8
P3_1
P3_2 P3_3
P3_4
P3_5
P3_6 P3_7
P3_8
P4_1
P4_2 P4_3
P4_4
P4_5
P4_6 P4_7
P4_8
NP1
NP2
A1
B1 C1
D1
A2
B2 C2
D2
A3
B3 C3
D3
A4
B4 C4
D4
A5
B5
D5
C5
NP3
NP4
TC7
ST68U16VDM-1-GP 
1 2
R361
100R2J-2-GP
1 2
R172
0R2J-2-GP
12
C23 
SCD1U50V3KX-GP 
1 2
C26 
SC1U25V3KX-1-GP 
1 2
C24 
SCD1U50V3KX-GP 
1 2
R186 0R2J-2-GP
DY
1 2
R60
4K7R2F-GP
1 2
PAD2
PAD-1P-424137-1-OG-GP
1
R150
10R2F-L-GP
1 2
R184 0R2J-2-GP1 2
TC5
ST68U16VDM-1-GP 
1 2
R620R2J-2-GP 12
TC1
ST68U16VDM-1-GP 
1 2
R151
10R2F-L-GP
1 2
TC3
ST68U16VDM-1-GP 
1 2
PAD1
PAD-1P-424137-2-OG-GP
1
C57 
SC220P50V3JN-GP 
DY
1 2
R175 0R2J-2-GP1 2
C56 
SC220P50V3JN-GP 
DY
1 2
H9
HOLE
1
H11
HOLE
1
C25 
SCD1U50V3KX-GP 
1 2
R173
0R2J-2-GP
12
R174 0R2J-2-GP1 2
R61
4K7R2F-GP
1 2
CN8
JWT-CON3-S11-GP
1
2
3
R358
10KR2F-2-GP
DY
1 2
TC6
ST68U16VDM-1-GP 
1 2
R360
100R2J-2-GP
1 2
TC4
ST15U25VDM-1-GP 
1 2
R362
100R2J-2-GP
DY
1 2
R359
10KR2F-2-GP
1 2
TC2
ST68U16VDM-1-GP 
1 2
TC8
ST15U25VDM-1-GP 
1 2
R171 0R2J-2-GP1 2
CN10
FCI-CONN52-4R-1-GP
P1_1
P1_2 P1_3
P1_4
P1_5
P1_6 P1_7
P1_8
P2_1
P2_2 P2_3
P2_4
P2_5
P2_6 P2_7
P2_8
P3_1
P3_2 P3_3
P3_4
P3_5
P3_6 P3_7
P3_8
P4_1
P4_2 P4_3
P4_4
P4_5
P4_6 P4_7
P4_8
NP1
NP2
A1
B1 C1
D1
A2
B2 C2
D2
A3
B3 C3
D3
A4
B4 C4
D4
A5
B5
D5
C5
NP3
NP4
H12
HOLE
1



5
5
4
4
3
3
2
2
1
1
D D
C C
B B
A A
Initial time= 4.3ms 
Pin2,Pin3 short 
(Default) 
Pin1,Pin2 short 
Jumper (JP1) 
Setting Mode Function 
OCP&OTP Latch 
OCP Latch and OTP auto re-try 
ADM1276_SS
ADM1276_Iset
ADM1276_VCAP
ADM1276_SENSE+
ADM1276_GATE_DRV
ADM1276_GATE_DRV1 
ADM1276_GATE_DRV2 
ADM1276_GATE_DRV3 
ADM1276_TIMER
ADM1276_VCC
ADM1276_SENSE-
P12V_SENSE_TRACE
ADM1276_ADR
ADM1276_GATE_RSV
ADM1276_GATE_RC
ADM1276_VOUT
ADM1276_PWRGD
ADM1276_GPIO2
ADM1276_OV
ADM1276_OV
ADM1276_UV
ADM1276_UV
ADM1276_GATE 
ADM1276_FLB
ADM1276_UVADM1276_LATCH#
ADM1276_VCAP
I2C_C_SDA_ADM1276
I2C_C_SCL_ADM1276
ADM1276_EN
SENSE+_R1 
SENSE-_R1 
SENSE+_R2 
SENSE-_R2 
SENSE-_R3 
SENSE-_R4 
SENSE+_R4 
SENSE+_R3 
ADM1276_EN_NET
ADM1276_LATCH_B
TEMP_ALM#_REVERSE
ADM1276_GATE_DRV0 
ADM1276_LATCH#
OTP_RETRY_B
OTP_RETRY_C OTP_RETRY_DIODE
ADM1276_EN
TEMP_ALM#_JP_1 
TEMP_ALM#_G
TEMP_ALM#_JP_2
OTP_RETRY_G
P12V_AUX
P12V_AUX
P12V
P12V
P12V
P3V3
P3V3
P12V_AUX
P12V_AUX
P12V_AUX
P12V_AUX
P12V_AUX
P12V_AUX
P3V3
P3V3
I2C_C_SCL3,6,7
I2C_C_SDA3,6,7
ADM1276_EN 10
TEMP_ALM#_REVERSE_R7
TEMP_ALM#3,10
Title 
Size Document Number Re v 
Date: Sheet o f 
Honey_Badger_FCB 1
HOT_SWAP ADM1276
Custom
8 13Friday, January 30, 2015
Wiwynn
H/W R&D Dept. II
8F,90,Sec. 1,Hsin Tai Wu Rd,
Hsichih, Taipei Hsien 221, Taiwan, R.O.C
Title 
Size Document Number Re v 
Date: Sheet o f 
Honey_Badger_FCB 1
HOT_SWAP ADM1276
Custom
8 13Friday, January 30, 2015
Wiwynn
H/W R&D Dept. II
8F,90,Sec. 1,Hsin Tai Wu Rd,
Hsichih, Taipei Hsien 221, Taiwan, R.O.C
Title 
Size Document Number Re v 
Date: Sheet o f 
Honey_Badger_FCB 1
HOT_SWAP ADM1276
Custom
8 13Friday, January 30, 2015
Wiwynn
H/W R&D Dept. II
8F,90,Sec. 1,Hsin Tai Wu Rd,
Hsichih, Taipei Hsien 221, Taiwan, R.O.C
S
S
S
G
D
PQ13
PH0925CL-GP
1
2
3
4
5
PR11
150KR2F-L-GP
DY
1 2
C261
SC10U25V6KX-1GP 
DY
1 2
PR46
51KR2F-L-GP
1 2
C58 
SCD1U25V2KX-GP 
1 2
PR16
1KR2F-3-GP
1 2
C51 
SCD1U10V2KX-4-LL-GP 
1 2
PR20 
10R2F-L-GP 
1 2
PR22 
10R2F-L-GP 
1 2
TC10 
ST68U16VDM-1-GP 
1 2
R364
0R2J-2-GP
1 2
PR35
4K7R2J-2-GP
DY1 2
R367
10KR2F-2-GP
1 2
PQ6
PMBS3904-1-GP
3
1
2
PR59
4K7R2F-GP
1 2 PQ14
PMBS3904-1-GP
3
1
2
PQ4
MMBT3906-3-GPC
B
E
PR36 
4K02R2F-GP 
1 2
PR26
10R2F-L-GP
1 2
TC9 
ST68U16VDM-1-GP 
1 2
PR29
D0005RL1632F-GP-U
1 2
3 4
PR7 
1KR2F-3-GP 
1 2
PC6
SCD022U50V3KX-2-GP
1 2
R365
10MR2J-L-GP 
1 2
PQ5
PMBS3904-1-GP
3
1
2
TP22
TPAD32-GP
1
PR10
0R0402-PAD-2-GP
1 2
PR42
10KR2F-2-GP
DY
1 2
PR3
51K1R2F-GP
1 2
PD1
MM3Z15VT1G-GP
DY
AK
D19
CH751H-40PT-1GP
KA
PR28
10R2F-L-GP
1 2
PR8
11KR2F-L-GP
1 2
PC4
SC1U25V3KX-1-GP
1 2
PR51
10R2F-L-GP
1 2
PC5
SCD01U25V2KX-3GP1 2
PR12 
0R2J-2-GP 
DY
1 2
PC3
SCD01U25V2KX-3GP
DY 1 2
C260
SC10U25V6KX-1GP 
DY
1 2
PR19 
10R2F-L-GP 
1 2
PR39
5K1R2F-2-GP
1 2
S
S
S
G
D
PQ3
PH0925CL-GP
1
2
3
4
5
PR1
100KR2F-L1-GP
1 2
R108 0R2J-2-GP1 2
PC7
SC1U25V5KX-1GP
DY
1 2
PR32
D0005RL1632F-GP-U
DY
1 2
3 4
PC1 
SC1U25V3KX-1-GP 
1 2
JP1
PIN-CON3-S3-GP
1
2
3
PR9
0R2J-2-GPDY1 2
PR2
10R2F-L-GP
1 2
PR58
10KR2F-2-GP
1 2
D18
CH751H-40PT-1GP
KA
PR49
4K7R2J-2-GP12
PD2
SMCJ15A-1-GP
AK
PR17 
10R2F-L-GP 
DY
1 2
PR18 
10R2F-L-GP 
1 2
PR23 
10R2F-L-GP 
1 2
Q10
2N7002DW-7F-GP
1
2
34
5
6
D14 
MBRS340T3G-GP 
AK
R366
10KR2F-2-GP
1 2
PR43
1K5R5J-GP
1 2
PR48
5K1R2F-2-GP
1 2PR40
54K9R2F-L-GP
1 2
PR33
51KR2F-L-GP
1 2
PR6
100KR2F-L1-GP
1 2
PR116
0R2J-2-GPDY
1 2
R363
5K1R2F-2-GP
DY
1 2
PC8 
SC1U25V5KX-1GP 
DY 
1 2
TC12 
ST15U25VDM-1-GP 
1 2
C259
SC10U25V6KX-1GP 
1 2
PR31
D0005RL1632F-GP-U
1 2
3 4
PR15
4K7R2J-2-GP
1 2
PU1
ADM1276-3ACPZ-RL-GP
ENABLE 8
GPO2/ALERT2# 9
PWRGD12
VOUT14
GND 15
VCC19
VCAP2
ISET 3SS 4
TIMER 5
FLB 13
SDA10
GATE 16
LATCH# 6
SCL11
ADR7
SENSE-17 SENSE+18
OV1
UV20
EP 21
PR21 
10R2F-L-GP 
1 2
PR25
0R2J-2-GPDY
12
PR24 
10R2F-L-GP 
DY1 2
PR14
0R2J-2-GP
1 2
PR27
10R2F-L-GP
1 2
PR5
0R2J-2-GP
DY1 2
S
S
S
G
D
PQ1
PH0925CL-GP
1
2
3
4
5
S
S
S
G
D
PQ2
PH0925CL-GP
1
2
3
4
5
PC2 
SC10U25V5KX-GP 
1 2
PR38
1KR2F-3-GP
1 2
PC10
SC1U25V5KX-1GP
1 2
TC11 
ST68U16VDM-1-GP 
1 2
PR4 
49K9R2F-L-GP 
1 2
PR34
51KR2F-L-GP
1 2
C255
SCD1U25V3KX-LL-GP
DY
1 2
PR37 
4K99R2F-L-GP 
1 2
PR30
D0005RL1632F-GP-U
1 2
3 4
PR41
1KR2F-3-GP
1 2
R109 0R2J-2-GP1 2
Q49
2N7002-11-GP
G
SD
PC9 
SC1U25V5KX-1GP 
1 2



5
5
4
4
3
3
2
2
1
1
D D
C C
B B
A A
FAN_TACH11
FAN_TACH12
FAN_TACH10
FAN_TACH9
FAN_TACH8
FAN_TACH7
FAN_TACH5
FAN_TACH4FAN_TACH3FAN_TACH2FAN_TACH1
P12V_FAN6
P12V_FAN4
P12V_FAN3
P12V_FAN2P12V_FAN1
P12V_FAN5
PWM_OUT_FAN2_NETPWM_OUT_FAN1_NET
PWM_OUT_FAN4_NET
PWM_OUT_FAN6_NET
PWM_OUT_FAN3_NET
PWM_OUT_FAN5_NET
FAN_TACH6
P12V
P12V
P12V
P12V
P12V
P12V
P12V
P12V
P12V
P12V
P12V
P12V
P12V
P12V
P12V
P12V
P12V
P12V
P12V
P12V
P12V
P12V
P12V
P12V
FANIN_113
FANIN_12 3
FANIN_93
FANIN_10 3
FANIN_73
FANIN_8 3
FANIN_5
FANIN_6 3
FANIN_33 FANIN_4 3FANIN_13 FANIN_2 3
PWM_OUT_FAN2 4
PWM_OUT_FAN6 4
PWM_OUT_FAN5 4
PWM_OUT_FAN4 4
PWM_OUT_FAN3 4
PWM_OUT_FAN1 4
Title 
Size 
Document Number Rev 
Date: Sheet o f 
Honey_Badger_FCB 1
FAN_CONN
C
9 13Friday, January 30, 2015
Wiwynn
H/W R&D Dept. II
8F,90,Sec. 1,Hsin Tai Wu Rd,
Hsichih, Taipei Hsien 221, Taiwan, R.O.C
Title 
Size 
Document Number Rev 
Date: Sheet o f 
Honey_Badger_FCB 1
FAN_CONN
C
9 13Friday, January 30, 2015
Wiwynn
H/W R&D Dept. II
8F,90,Sec. 1,Hsin Tai Wu Rd,
Hsichih, Taipei Hsien 221, Taiwan, R.O.C
Title 
Size 
Document Number Rev 
Date: Sheet o f 
Honey_Badger_FCB 1
FAN_CONN
C
9 13Friday, January 30, 2015
Wiwynn
H/W R&D Dept. II
8F,90,Sec. 1,Hsin Tai Wu Rd,
Hsichih, Taipei Hsien 221, Taiwan, R.O.C
C31 
SCD1U50V3KX-GP 
1 2
C27 
SCD1U16V2KX-3GP 
DY
1 2
R104 
10KR2F-2-GP 
1 2 R177
0R1206-PAD-1-GP
1 2
C35 
SCD1U16V2KX-3GP 
DY
1 2
CN6
JWT-CON5-42-GP
1
2
3
4
5
TC16
ST15U25VDM-1-GP 
1 2
C38 
SCD1U16V2KX-3GP 
DY
1 2
R99
27KR3F-GP
1 2
R68 
4K7R2F-GP 
1 2
D1 
BAS16H-GP 
K A
R70
27KR3F-GP
1 2
R102 
10KR2F-2-GP 
1 2
D10 
BAS16H-GP 
K A
R179
0R1206-PAD-1-GP
1 2
C29 
SCD1U16V2KX-3GP 
DY
1 2
D4 
BAS16H-GP 
K A
R83 
4K7R2F-GP 
1 2
F1
FUSE-3A15V-GP
DY1 2
C28 
SCD1U16V2KX-3GP 
DY
1 2
C32 
SC1U25V3KX-1-GP 
1 2
R141
0R2J-2-GP
1 2
F5
FUSE-3A15V-GP
DY1 2
C37 
SCD1U16V2KX-3GP 
DY
1 2
C41 
SCD1U50V3KX-GP 
1 2
D8 
BAS16H-GP 
K A
C49 
SCD1U50V3KX-GP 
1 2
R182
0R1206-PAD-1-GP
1 2
TC13
ST15U25VDM-1-GP 
1 2
CN1
JWT-CON5-42-GP
1
2
3
4
5
R67 
4K7R2F-GP 
1 2
R93 
4K7R2F-GP 
1 2
C36 
SCD1U16V2KX-3GP 
DY
1 2
R72
27KR3F-GP
1 2
R92
4K7R2F-GP
DY
1 2
R87
27KR3F-GP
1 2
R140
0R2J-2-GP
1 2
C33 
SCD1U50V3KX-GP 
1 2
TC15
ST15U25VDM-1-GP 
1 2
R71
27KR3F-GP
1 2
R137
0R2J-2-GP
1 2
C47 
SCD1U50V3KX-GP 
1 2
CN2
JWT-CON5-42-GP
1
2
3
4
5
R96
4K7R2F-GP 
DY
1 2
D2 
BAS16H-GP 
K A
R85
27KR3F-GP
1 2
R86
27KR3F-GP
1 2
CN3
JWT-CON5-42-GP
1
2
3
4
5
C43 
SCD1U16V2KX-3GP 
DY
1 2
R90 
10KR2F-2-GP 
1 2
D12 
BAS16H-GP 
K A
R66 
4K7R2F-GP 
1 2
R95 
4K7R2F-GP 
1 2
R65
4K7R2F-GP 
DY
1 2
R178
0R1206-PAD-1-GP
1 2
R73
27KR3F-GP
1 2
R74 
10KR2F-2-GP 
1 2
D9 
BAS16H-GP 
K A
F6
FUSE-3A15V-GP
DY1 2
D5 
BAS16H-GP 
K A
C48 
SC1U25V3KX-1-GP 
1 2
R181
0R1206-PAD-1-GP
1 2
TC18
ST15U25VDM-1-GP 
1 2
R136
0R2J-2-GP
1 2
C39 
SCD1U50V3KX-GP 
1 2
R82 
4K7R2F-GP 
1 2
C44 
SCD1U16V2KX-3GP 
DY
1 2
C50 
SC1U25V3KX-1-GP 
1 2
D11 
BAS16H-GP 
K A
R103
10KR2F-2-GP1 2
D6 
BAS16H-GP 
K A
C42 
SC1U25V3KX-1-GP 
1 2
R81 
4K7R2F-GP 
1 2
TC14
ST15U25VDM-1-GP 
1 2
R64
4K7R2F-GP DY
1 2
D3 
BAS16H-GP 
K A
R105 
10KR2F-2-GP 
1 2
TC17 
ST15U25VDM-1-GP 
1 2
R89 
10KR2F-2-GP 
1 2
C46 
SCD1U16V2KX-3GP 
DY
1 2
R76 
10KR2F-2-GP 
1 2
D7 
BAS16H-GP 
K A
R84
27KR3F-GP
1 2
C45 
SCD1U16V2KX-3GP 
DY
1 2
R94 
4K7R2F-GP 
1 2
C34 
SC1U25V3KX-1-GP 
1 2
C40 
SC1U25V3KX-1-GP 
1 2
R100
27KR3F-GP
1 2
CN5
JWT-CON5-42-GP
1
2
3
4
5
R97 
4K7R2F-GP 
1 2
R78
4K7R2F-GP 
DY1 2
R88 
10KR2F-2-GP 
1 2
R79
4K7R2F-GP 
DY
1 2
R180
0R1206-PAD-1-GP
1 2
F4
FUSE-3A15V-GP
DY1 2
R101
27KR3F-GP
1 2
R91 
10KR2F-2-GP 
1 2
R69 
4K7R2F-GP 
1 2
F2
FUSE-3A15V-GP
DY1 2
CN4
JWT-CON5-42-GP
1
2
3
4
5
R80 
4K7R2F-GP 
1 2
R77 
10KR2F-2-GP 
1 2
R139
0R2J-2-GP
1 2
R75 
10KR2F-2-GP 
1 2
C30 
SCD1U16V2KX-3GP 
DY
1 2
F3
FUSE-3A15V-GP
DY1 2
R138
0R2J-2-GP
1 2
R98
27KR3F-GP
1 2



5
5
4
4
3
3
2
2
1
1
D D
C C
B B
A A
P12VU_2490_SENSE
P12VU_2490_PG
P12VU_2490_TIMER 
P12VU_2490_VCC
P12VU_2490_RC P12VL_2490_SENSE
P12VL_2490_VREF
P12VL_2490_TIMER 
P12VL_2490_VCC
P12VL_2490_RC
P12VU_2490_GATE_DRV 
P12VL_2490_GATE_DRV P12VL_2490_GATE 
P12VU_2490_GATE 
P12VL_2490_PG
P12VU_2490_VREF
P12VL_2490_PROG 
P12VU_2490_PROG 
P3V3_AUX_BJT_B
TEMP_ALM#_IN
D_LATCH_PRE# 
D_LATCH_CLR
D_LATCH_Q#
TEMP_ALM#_IN_D
D_LATCH_Q
P12VU_NET P12VL_NET
P12VU_2490_GATE_DRV_2 
P12VL_2490_GATE_DRV_2 
P12VU_2490_EN_2 P12VL_2490_EN_2
P12V
P12VU P12V P12VL
P3V3_AUX
P12V_AUX
P3V3_AUX
P3V3_AUX
P3V3_AUX
P3V3_AUX
P3V3_AUX
P3V3_AUX
P3V3_AUX
P12V
P12V
TEMP_ALM#3,8
ADM1276_EN 8
P12VL_2490_EN_27
P12VU_2490_EN_27
P12VU_2490_EN_17
P12VL_2490_EN_17
D_LATCH_PRE#7
Title 
Size 
Document Number Rev 
Date: Sheet o f 
Honey_Badger_FCB 1
HOT SWAP TPS2490
C
10 13Friday, January 30, 2015
Wiwynn
H/W R&D Dept. II
8F,90,Sec. 1,Hsin Tai Wu Rd,
Hsichih, Taipei Hsien 221, Taiwan, R.O.C
Title 
Size 
Document Number Rev 
Date: Sheet o f 
Honey_Badger_FCB 1
HOT SWAP TPS2490
C
10 13Friday, January 30, 2015
Wiwynn
H/W R&D Dept. II
8F,90,Sec. 1,Hsin Tai Wu Rd,
Hsichih, Taipei Hsien 221, Taiwan, R.O.C
Title 
Size 
Document Number Rev 
Date: Sheet o f 
Honey_Badger_FCB 1
HOT SWAP TPS2490
C
10 13Friday, January 30, 2015
Wiwynn
H/W R&D Dept. II
8F,90,Sec. 1,Hsin Tai Wu Rd,
Hsichih, Taipei Hsien 221, Taiwan, R.O.C
PC90
SCD1U25V2KX-GP
1 2
C253 
SC4D7U6D3V3KX-GP 
1 2
PR109 
6K81R2F-1-GP 
1 2
PR102
10R2F-L-GP
1 2
D15 
MBRS340T3G-GP 
AK
PR119
10R2F-L-GP
1 2
R261
10KR2J-3-GP
1 2
PR45
10KR2F-2-GP
1 2
PR98
1MR3J-L-GP
DY
1 2
PR63
D002R2512F-GP
1 2
PR95
0R2J-2-GP
12
PR118
10R2F-L-GP
1 2
TP24
TPAD32-GP
1
C254
SCD1U16V2KX-3GP
1 2
PR111
178KR2F-GP
1 2
C258 
SC1U25V3KX-1-GP 
1 2
PR61
D002R2512F-GP
1 2
PC86
SCD01U25V2KX-3GP
1 2
PC96 
SCD1U50V3KX-GP 
1 2
S
S
S
G
D
PQ11
PH0925CL-GP
1
2
3
4
5
D16 
MBRS340T3G-GP 
AK
PQ10
PMBS3904-1-GP
3
1
2
PR97
0R2J-2-GP
12
PR104
2K7R2F-GP
1 2
PC93
SC220P50V2KX-3GP
1 2
PR105
2K7R2F-GP
1 2TP23
TPAD32-GP
1
PC95 
SC10U25V5KX-GP 
1 2
PR44
1KR2F-3-GP
DY
1 2
U8A
TSAHC74PWR-GP
D2
CLK3
Q 5
Q# 6
VCC14
PRE# 4
GND7
CLR# 1
S
S
S
G
D
PQ8
PH0925CL-GP
1
2
3
4
5
PC85
SCD01U25V2KX-3GP
1 2
PC87
SC220P50V2KX-3GP
12
PC97 
SC10U25V5KX-GP 
DY1 2
PR101
100R2F-L1-GP-U
1 2
PC91
SCD01U50V3KX-4GP
1 2
PR117
3K3R3F-GP
1 2
PR114 
20KR2F-L-GP 
1 2
PR47
4K7R2J-2-GP
1 2
PC94
SC220P50V2KX-3GP
1 2
S
S
S
G
D
PQ7
PH0925CL-GP
1
2
3
4
5
PC98 
SCD1U50V3KX-GP 
DY1 2
PR103
10R2F-L-GP
1 2
PC89
SCD1U25V2KX-GP
1 2
S
S
S
G
D
PQ12
PH0925CL-GP
1
2
3
4
5
PR115 
20KR2F-L-GP 
1 2
PQ9
PMBS3904-1-GP
3
1
2
PR62
D002R2512F-GP
1 2
PC92
SCD01U50V3KX-4GP
1 2
PR94
0R2J-2-GP
12
PR96
12
PR60
D002R2512F-GP
1 2
PU7
TPS2490DGSR-GP
EN1
VREF2
PROG 3
TIMER 4
GND 5
PG 6
OUT 7
GATE 8
SENSE 9
VCC 10 
PR112
6K81R2F-1-GP
1 2
PR99
100R2F-L1-GP-U
1 2
PR107
1KR2F-3-GP
1 2
U8B
TSAHC74PWR-GP
D12
CLK11
Q 9
Q# 8
VCC14
PRE# 10 
GND7
CLR# 13 
PR100
1MR3J-L-GP
DY
1 2
PR106
1KR2F-3-GP
1 2
PU6
TPS2490DGSR-GP
EN1
VREF2
PROG 3
TIMER 4
GND 5
PG 6
OUT 7
GATE 8
SENSE 9
VCC 10 
R260
47KR2J-2-GP
1 2
C256
SCD1U16V2KX-3GP
1 2
C257 
SC1U25V3KX-1-GP 
1 2
PR108 
6K81R2F-1-GP 
1 2
D13
BZG05C3V9-GP
K A
PR113
6K81R2F-1-GP
1 2
PC1262 
SC10U16V6KX-2GP 
1 2
PC88
SC220P50V2KX-3GP
12
R270
0R2J-2-GP
DY
1 2
TP21
TPAD32-GP
1
PR110
178KR2F-GP
1 2



5
5
4
4
3
3
2
2
1
1
D D
C C
B B
A A
Title 
Size Document Number R e v 
Date: Sheet 
o f 
Honey_Badger_FCB 1
Screws
A3
11 13Friday, January 30, 2015
Wiwynn
H/W R&D Dept. II
8F,90,Sec. 1,Hsin Tai Wu Rd,
Hsichih, Taipei Hsien 221, Taiwan, R.O.C
Title 
Size Document Number R e v 
Date: Sheet 
o f 
Honey_Badger_FCB 1
Screws
A3
11 13Friday, January 30, 2015
Wiwynn
H/W R&D Dept. II
8F,90,Sec. 1,Hsin Tai Wu Rd,
Hsichih, Taipei Hsien 221, Taiwan, R.O.C
Title 
Size Document Number R e v 
Date: Sheet 
o f 
Honey_Badger_FCB 1
Screws
A3
11 13Friday, January 30, 2015
Wiwynn
H/W R&D Dept. II
8F,90,Sec. 1,Hsin Tai Wu Rd,
Hsichih, Taipei Hsien 221, Taiwan, R.O.C
H6
HOLE
1
H3
HOLE
1
H5
HOLE
1
H13
HOLE
1
H2
HOLE
1
H8
HOLE
1
H1
HOLE
1
H4
HOLE
1
H7
HOLE
1



5
5
4
4
3
3
2
2
1
1
D D
C C
B B
A A
BLANK 
Title 
Size 
Document Number Rev 
Date: Sheet o f 
Honey_Badger_FCB 1
BLANK
C
12 13Friday, January 30, 2015
Wiwynn
H/W R&D Dept. II
8F,90,Sec. 1,Hsin Tai Wu Rd,
Hsichih, Taipei Hsien 221, Taiwan, R.O.C
Title 
Size 
Document Number Rev 
Date: Sheet o f 
Honey_Badger_FCB 1
BLANK
C
12 13Friday, January 30, 2015
Wiwynn
H/W R&D Dept. II
8F,90,Sec. 1,Hsin Tai Wu Rd,
Hsichih, Taipei Hsien 221, Taiwan, R.O.C
Title 
Size 
Document Number Rev 
Date: Sheet o f 
Honey_Badger_FCB 1
BLANK
C
12 13Friday, January 30, 2015
Wiwynn
H/W R&D Dept. II
8F,90,Sec. 1,Hsin Tai Wu Rd,
Hsichih, Taipei Hsien 221, Taiwan, R.O.C



5
5
4
4
3
3
2
2
1
1
D D
C C
B B
A A
BLANK 
Title 
Size 
Document Number Rev 
Date: Sheet o f 
Honey_Badger_FCB 1
BLANK
C
13 13Friday, January 30, 2015
Wiwynn
H/W R&D Dept. II
8F,90,Sec. 1,Hsin Tai Wu Rd,
Hsichih, Taipei Hsien 221, Taiwan, R.O.C
Title 
Size 
Document Number Rev 
Date: Sheet o f 
Honey_Badger_FCB 1
BLANK
C
13 13Friday, January 30, 2015
Wiwynn
H/W R&D Dept. II
8F,90,Sec. 1,Hsin Tai Wu Rd,
Hsichih, Taipei Hsien 221, Taiwan, R.O.C
Title 
Size 
Document Number Rev 
Date: Sheet o f 
Honey_Badger_FCB 1
BLANK
C
13 13Friday, January 30, 2015
Wiwynn
H/W R&D Dept. II
8F,90,Sec. 1,Hsin Tai Wu Rd,
Hsichih, Taipei Hsien 221, Taiwan, R.O.C



5
5
4
4
3
3
2
2
1
1
D D
C C
B B
A A
BLANK 
Title 
Size 
Document Number Rev 
Date: Sheet o f 
Honey_Badger_FCB 1
BLANK
C
14 14Friday, January 30, 2015
Wiwynn
H/W R&D Dept. II
8F,90,Sec. 1,Hsin Tai Wu Rd,
Hsichih, Taipei Hsien 221, Taiwan, R.O.C
Title 
Size 
Document Number Rev 
Date: Sheet o f 
Honey_Badger_FCB 1
BLANK
C
14 14Friday, January 30, 2015
Wiwynn
H/W R&D Dept. II
8F,90,Sec. 1,Hsin Tai Wu Rd,
Hsichih, Taipei Hsien 221, Taiwan, R.O.C
Title 
Size 
Document Number Rev 
Date: Sheet o f 
Honey_Badger_FCB 1
BLANK
C
14 14Friday, January 30, 2015
Wiwynn
H/W R&D Dept. II
8F,90,Sec. 1,Hsin Tai Wu Rd,
Hsichih, Taipei Hsien 221, Taiwan, R.O.C